(kicad_pcb
	(version 20260206)
	(generator "pcbnew")
	(generator_version "10.0")
	(general
		(thickness 1.6)
		(legacy_teardrops no)
	)
	(paper "A4")
	(title_block
		(title "04192023_DAF0TMB3IC0_F0TG_MB_C_brd_V02_OCP.brd")
		(comment 1 "Grand Teton / footprints 5355-5361 of 8354")
	)
	(layers
		(0 "F.Cu" signal "TOP")
		(4 "In1.Cu" signal "GND")
		(6 "In2.Cu" signal "IN1")
		(8 "In3.Cu" signal "GND1")
		(10 "In4.Cu" signal "IN2")
		(12 "In5.Cu" signal "GND2")
		(14 "In6.Cu" signal "IN3")
		(16 "In7.Cu" signal "GND3")
		(18 "In8.Cu" signal "VCC")
		(20 "In9.Cu" signal "VCC1")
		(22 "In10.Cu" signal "GND4")
		(24 "In11.Cu" signal "IN4")
		(26 "In12.Cu" signal "GND5")
		(28 "In13.Cu" signal "IN5")
		(30 "In14.Cu" signal "GND6")
		(32 "In15.Cu" signal "IN6")
		(34 "In16.Cu" signal "GND7")
		(2 "B.Cu" signal "BOTTOM")
		(9 "F.Adhes" user "F.Adhesive")
		(11 "B.Adhes" user "B.Adhesive")
		(13 "F.Paste" user "Package Geometry/Pastemask Top")
		(15 "B.Paste" user "Package Geometry/Pastemask Bottom")
		(5 "F.SilkS" user "Ref Des/Silkscreen Top")
		(7 "B.SilkS" user "Ref Des/Silkscreen Bottom")
		(1 "F.Mask" user "Board Geometry/Soldermask Top")
		(3 "B.Mask" user "Board Geometry/Soldermask Bottom")
		(17 "Dwgs.User" user "User.Drawings")
		(19 "Cmts.User" user "User.Comments")
		(21 "Eco1.User" user "User.Eco1")
		(23 "Eco2.User" user "User.Eco2")
		(25 "Edge.Cuts" user "Board Geometry/Outline")
		(27 "Margin" user)
		(31 "F.CrtYd" user "Package Geometry/Place Bound Top")
		(29 "B.CrtYd" user "Package Geometry/Place Bound Bottom")
		(35 "F.Fab" user "Ref Des/Assembly Top")
		(33 "B.Fab" user "Ref Des/Assembly Bottom")
	)
	(footprint ""
		(layer "B.Cu")
		(at 100.628704 -331.279754 -90)
		(property "Reference" "PC149_6"
			(at 0 0 90)
			(layer "B.SilkS")
			(hide yes)
			(effects
				(font
					(size 1.27 1.27)
				)
				(justify mirror)
			)
		)
		(property "Value" ""
			(at 0 0 90)
			(layer "B.Fab")
			(effects
				(font
					(size 1.27 1.27)
				)
				(justify mirror)
			)
		)
		(duplicate_pad_numbers_are_jumpers no)
		(fp_line
			(start -1.524 0.762)
			(end 1.524 0.762)
			(stroke
				(width 0.1524)
				(type default)
			)
			(layer "B.SilkS")
		)
		(fp_line
			(start 1.524 0.762)
			(end 1.524 -0.762)
			(stroke
				(width 0.1524)
				(type default)
			)
			(layer "B.SilkS")
		)
		(fp_line
			(start -1.524 -0.762)
			(end -1.524 0.762)
			(stroke
				(width 0.1524)
				(type default)
			)
			(layer "B.SilkS")
		)
		(fp_line
			(start 1.524 -0.762)
			(end -1.524 -0.762)
			(stroke
				(width 0.1524)
				(type default)
			)
			(layer "B.SilkS")
		)
		(fp_line
			(start -1.1049 0.724916)
			(end -1.1049 -0.724916)
			(stroke
				(width 0.1)
				(type default)
			)
			(layer "B.Fab")
		)
		(fp_line
			(start 1.1049 0.724916)
			(end -1.1049 0.724916)
			(stroke
				(width 0.1)
				(type default)
			)
			(layer "B.Fab")
		)
		(fp_line
			(start -1.1049 -0.724916)
			(end 1.1049 -0.724916)
			(stroke
				(width 0.1)
				(type default)
			)
			(layer "B.Fab")
		)
		(fp_line
			(start 1.1049 -0.724916)
			(end 1.1049 0.724916)
			(stroke
				(width 0.1)
				(type default)
			)
			(layer "B.Fab")
		)
		(pad "1" smd rect
			(at 0.889 0 270)
			(size 1.016 1.27)
			(layers "B.Cu" "B.Mask" "B.Paste")
			(net "PVDDCR_CPU1_P1")
		)
		(pad "2" smd rect
			(at -0.889 0 270)
			(size 1.016 1.27)
			(layers "B.Cu" "B.Mask" "B.Paste")
			(net "GND")
		)
	)
	(footprint ""
		(layer "B.Cu")
		(at 188.849 -422.402)
		(property "Reference" "R8107"
			(at 0 0 0)
			(layer "B.SilkS")
			(hide yes)
			(effects
				(font
					(size 1.27 1.27)
				)
				(justify mirror)
			)
		)
		(property "Value" ""
			(at 0 0 0)
			(layer "B.Fab")
			(effects
				(font
					(size 1.27 1.27)
				)
				(justify mirror)
			)
		)
		(duplicate_pad_numbers_are_jumpers no)
		(fp_line
			(start -0.7874 -0.4064)
			(end -0.7874 0.4064)
			(stroke
				(width 0.1524)
				(type default)
			)
			(layer "B.SilkS")
		)
		(fp_line
			(start -0.7874 0.4064)
			(end 0.7874 0.4064)
			(stroke
				(width 0.1524)
				(type default)
			)
			(layer "B.SilkS")
		)
		(fp_line
			(start 0.7874 -0.4064)
			(end -0.7874 -0.4064)
			(stroke
				(width 0.1524)
				(type default)
			)
			(layer "B.SilkS")
		)
		(fp_line
			(start 0.7874 0.4064)
			(end 0.7874 -0.4064)
			(stroke
				(width 0.1524)
				(type default)
			)
			(layer "B.SilkS")
		)
		(fp_line
			(start -0.67945 -0.3048)
			(end -0.67945 0.3048)
			(stroke
				(width 0.1)
				(type default)
			)
			(layer "B.Fab")
		)
		(fp_line
			(start -0.67945 0.3048)
			(end -0.120396 0.3048)
			(stroke
				(width 0.1)
				(type default)
			)
			(layer "B.Fab")
		)
		(fp_line
			(start -0.12065 -0.3048)
			(end -0.67945 -0.3048)
			(stroke
				(width 0.1)
				(type default)
			)
			(layer "B.Fab")
		)
		(fp_line
			(start -0.12065 -0.2794)
			(end -0.12065 -0.3048)
			(stroke
				(width 0.1)
				(type default)
			)
			(layer "B.Fab")
		)
		(fp_line
			(start -0.120396 0.2794)
			(end 0.12065 0.2794)
			(stroke
				(width 0.1)
				(type default)
			)
			(layer "B.Fab")
		)
		(fp_line
			(start -0.120396 0.3048)
			(end -0.120396 0.2794)
			(stroke
				(width 0.1)
				(type default)
			)
			(layer "B.Fab")
		)
		(fp_line
			(start 0.12065 -0.305054)
			(end 0.12065 -0.2794)
			(stroke
				(width 0.1)
				(type default)
			)
			(layer "B.Fab")
		)
		(fp_line
			(start 0.12065 -0.2794)
			(end -0.12065 -0.2794)
			(stroke
				(width 0.1)
				(type default)
			)
			(layer "B.Fab")
		)
		(fp_line
			(start 0.12065 0.2794)
			(end 0.12065 0.3048)
			(stroke
				(width 0.1)
				(type default)
			)
			(layer "B.Fab")
		)
		(fp_line
			(start 0.12065 0.3048)
			(end 0.67945 0.3048)
			(stroke
				(width 0.1)
				(type default)
			)
			(layer "B.Fab")
		)
		(fp_line
			(start 0.67945 -0.305054)
			(end 0.12065 -0.305054)
			(stroke
				(width 0.1)
				(type default)
			)
			(layer "B.Fab")
		)
		(fp_line
			(start 0.67945 0.3048)
			(end 0.67945 -0.305054)
			(stroke
				(width 0.1)
				(type default)
			)
			(layer "B.Fab")
		)
		(pad "1" smd circle
			(at 0.40005 0 180)
			(size 0 0)
			(layers "B.Cu" "B.Mask" "B.Paste")
			(net "P3V3_AUX")
		)
		(pad "2" smd circle
			(at -0.40005 0 180)
			(size 0 0)
			(layers "B.Cu" "B.Mask" "B.Paste")
			(net "OC_P2V5_COMP")
		)
	)
	(footprint ""
		(layer "B.Cu")
		(at 210.83905 -69.530468)
		(property "Reference" "U7"
			(at 2.032 -3.27533 0)
			(unlocked yes)
			(layer "B.SilkS")
			(effects
				(font
					(size 0.7874 0.5842)
					(thickness 0.1524)
				)
				(justify left mirror)
			)
		)
		(property "Value" ""
			(at 0 0 0)
			(layer "B.Fab")
			(effects
				(font
					(size 1.27 1.27)
				)
				(justify mirror)
			)
		)
		(duplicate_pad_numbers_are_jumpers no)
		(fp_line
			(start -2.0066 -2.5527)
			(end -2.0066 2.5527)
			(stroke
				(width 0.1524)
				(type default)
			)
			(layer "B.SilkS")
		)
		(fp_line
			(start -2.0066 2.5527)
			(end 2.0066 2.5527)
			(stroke
				(width 0.1524)
				(type default)
			)
			(layer "B.SilkS")
		)
		(fp_line
			(start -0.5715 -2.5527)
			(end -2.0066 -2.5527)
			(stroke
				(width 0.1524)
				(type default)
			)
			(layer "B.SilkS")
		)
		(fp_line
			(start 0 -1.9812)
			(end -0.5715 -2.5527)
			(stroke
				(width 0.1524)
				(type default)
			)
			(layer "B.SilkS")
		)
		(fp_line
			(start 0.5715 -2.5527)
			(end 0 -1.9812)
			(stroke
				(width 0.1524)
				(type default)
			)
			(layer "B.SilkS")
		)
		(fp_line
			(start 2.0066 -2.5527)
			(end 0.5715 -2.5527)
			(stroke
				(width 0.1524)
				(type default)
			)
			(layer "B.SilkS")
		)
		(fp_line
			(start 2.0066 2.5527)
			(end 2.0066 -2.5527)
			(stroke
				(width 0.1524)
				(type default)
			)
			(layer "B.SilkS")
		)
		(fp_poly
			(pts
				(xy 3.179318 -2.37617) (xy 2.893822 -2.953258) (xy 3.516884 -2.906014)
			)
			(stroke
				(width 0)
				(type default)
			)
			(fill yes)
			(layer "B.SilkS")
		)
		(fp_line
			(start -2.249932 -2.549906)
			(end -2.249932 2.549906)
			(stroke
				(width 0.1)
				(type default)
			)
			(layer "B.Fab")
		)
		(fp_line
			(start -2.249932 2.549906)
			(end 2.249932 2.549906)
			(stroke
				(width 0.1)
				(type default)
			)
			(layer "B.Fab")
		)
		(fp_line
			(start 2.249932 -2.549906)
			(end -2.249932 -2.549906)
			(stroke
				(width 0.1)
				(type default)
			)
			(layer "B.Fab")
		)
		(fp_line
			(start 2.249932 2.549906)
			(end 2.249932 -2.549906)
			(stroke
				(width 0.1)
				(type default)
			)
			(layer "B.Fab")
		)
		(fp_poly
			(pts
				(xy 4.36372 -1.608328) (xy 4.36372 -2.233168) (xy 3.81 -1.905)
			)
			(stroke
				(width 0)
				(type default)
			)
			(fill yes)
			(layer "B.Fab")
		)
		(pad "1" smd rect
			(at 2.921 -1.949958 270)
			(size 0.3556 1.4986)
			(layers "B.Cu" "B.Mask" "B.Paste")
			(net "FB_BMC_ISOLATE")
		)
		(pad "2" smd rect
			(at 2.921 -1.299972 270)
			(size 0.3556 1.4986)
			(layers "B.Cu" "B.Mask" "B.Paste")
			(net "NCSI_BMC_TXD1_R")
		)
		(pad "3" smd rect
			(at 2.921 -0.649986 270)
			(size 0.3556 1.4986)
			(layers "B.Cu" "B.Mask" "B.Paste")
			(net "NCSI_OCP_SFF_TXD1")
		)
		(pad "4" smd rect
			(at 2.921 0 270)
			(size 0.3556 1.4986)
			(layers "B.Cu" "B.Mask" "B.Paste")
			(net "FB_BMC_ISOLATE")
		)
		(pad "5" smd rect
			(at 2.921 0.649986 270)
			(size 0.3556 1.4986)
			(layers "B.Cu" "B.Mask" "B.Paste")
			(net "NCSI_BMC_TXD0_R")
		)
		(pad "6" smd rect
			(at 2.921 1.299972 270)
			(size 0.3556 1.4986)
			(layers "B.Cu" "B.Mask" "B.Paste")
			(net "NCSI_OCP_SFF_TXD0")
		)
		(pad "7" smd rect
			(at 2.921 1.949958 270)
			(size 0.3556 1.4986)
			(layers "B.Cu" "B.Mask" "B.Paste")
			(net "GND")
		)
		(pad "8" smd rect
			(at -2.921 1.949958 270)
			(size 0.3556 1.4986)
			(layers "B.Cu" "B.Mask" "B.Paste")
			(net "NCSI_OCP_SFF_TX_EN")
		)
		(pad "9" smd rect
			(at -2.921 1.299972 270)
			(size 0.3556 1.4986)
			(layers "B.Cu" "B.Mask" "B.Paste")
			(net "NCSI_BMC_TX_EN_R")
		)
		(pad "10" smd rect
			(at -2.921 0.649986 270)
			(size 0.3556 1.4986)
			(layers "B.Cu" "B.Mask" "B.Paste")
			(net "FB_BMC_ISOLATE")
		)
		(pad "11" smd rect
			(at -2.921 0 270)
			(size 0.3556 1.4986)
			(layers "B.Cu" "B.Mask" "B.Paste")
			(net "OCP_SFF_ISO2_RBT_ARB_OUT")
		)
		(pad "12" smd rect
			(at -2.921 -0.649986 270)
			(size 0.3556 1.4986)
			(layers "B.Cu" "B.Mask" "B.Paste")
			(net "OCP_SFF_RBT_ARB_OUT")
		)
		(pad "13" smd rect
			(at -2.921 -1.299972 270)
			(size 0.3556 1.4986)
			(layers "B.Cu" "B.Mask" "B.Paste")
			(net "FB_BMC_ISOLATE")
		)
		(pad "14" smd rect
			(at -2.921 -1.949958 270)
			(size 0.3556 1.4986)
			(layers "B.Cu" "B.Mask" "B.Paste")
			(net "P3V3_AUX")
		)
	)
	(footprint ""
		(layer "B.Cu")
		(at 346.532454 -256.73431 180)
		(property "Reference" "C2625"
			(at 0 0 0)
			(layer "B.SilkS")
			(hide yes)
			(effects
				(font
					(size 1.27 1.27)
				)
				(justify mirror)
			)
		)
		(property "Value" ""
			(at 0 0 0)
			(layer "B.Fab")
			(effects
				(font
					(size 1.27 1.27)
				)
				(justify mirror)
			)
		)
		(duplicate_pad_numbers_are_jumpers no)
		(fp_line
			(start 0.7874 0.4064)
			(end 0.7874 -0.4064)
			(stroke
				(width 0.1524)
				(type default)
			)
			(layer "B.SilkS")
		)
		(fp_line
			(start 0.7874 -0.4064)
			(end -0.7874 -0.4064)
			(stroke
				(width 0.1524)
				(type default)
			)
			(layer "B.SilkS")
		)
		(fp_line
			(start -0.7874 0.4064)
			(end 0.7874 0.4064)
			(stroke
				(width 0.1524)
				(type default)
			)
			(layer "B.SilkS")
		)
		(fp_line
			(start -0.7874 -0.4064)
			(end -0.7874 0.4064)
			(stroke
				(width 0.1524)
				(type default)
			)
			(layer "B.SilkS")
		)
		(fp_line
			(start 0.67945 0.3048)
			(end 0.67945 -0.305054)
			(stroke
				(width 0.1)
				(type default)
			)
			(layer "B.Fab")
		)
		(fp_line
			(start 0.67945 -0.305054)
			(end 0.12065 -0.305054)
			(stroke
				(width 0.1)
				(type default)
			)
			(layer "B.Fab")
		)
		(fp_line
			(start 0.12065 0.3048)
			(end 0.67945 0.3048)
			(stroke
				(width 0.1)
				(type default)
			)
			(layer "B.Fab")
		)
		(fp_line
			(start 0.12065 0.2794)
			(end 0.12065 0.3048)
			(stroke
				(width 0.1)
				(type default)
			)
			(layer "B.Fab")
		)
		(fp_line
			(start 0.12065 -0.2794)
			(end -0.12065 -0.2794)
			(stroke
				(width 0.1)
				(type default)
			)
			(layer "B.Fab")
		)
		(fp_line
			(start 0.12065 -0.305054)
			(end 0.12065 -0.2794)
			(stroke
				(width 0.1)
				(type default)
			)
			(layer "B.Fab")
		)
		(fp_line
			(start -0.120396 0.3048)
			(end -0.120396 0.2794)
			(stroke
				(width 0.1)
				(type default)
			)
			(layer "B.Fab")
		)
		(fp_line
			(start -0.120396 0.2794)
			(end 0.12065 0.2794)
			(stroke
				(width 0.1)
				(type default)
			)
			(layer "B.Fab")
		)
		(fp_line
			(start -0.12065 -0.2794)
			(end -0.12065 -0.3048)
			(stroke
				(width 0.1)
				(type default)
			)
			(layer "B.Fab")
		)
		(fp_line
			(start -0.12065 -0.3048)
			(end -0.67945 -0.3048)
			(stroke
				(width 0.1)
				(type default)
			)
			(layer "B.Fab")
		)
		(fp_line
			(start -0.67945 0.3048)
			(end -0.120396 0.3048)
			(stroke
				(width 0.1)
				(type default)
			)
			(layer "B.Fab")
		)
		(fp_line
			(start -0.67945 -0.3048)
			(end -0.67945 0.3048)
			(stroke
				(width 0.1)
				(type default)
			)
			(layer "B.Fab")
		)
		(pad "1" smd circle
			(at 0.40005 0)
			(size 0 0)
			(layers "B.Cu" "B.Mask" "B.Paste")
			(net "PVDDIO_P0")
		)
		(pad "2" smd circle
			(at -0.40005 0)
			(size 0 0)
			(layers "B.Cu" "B.Mask" "B.Paste")
			(net "GND")
		)
	)
	(footprint ""
		(layer "B.Cu")
		(at 119.418354 -388.011162 -90)
		(property "Reference" "C463"
			(at 0 0 90)
			(layer "B.SilkS")
			(hide yes)
			(effects
				(font
					(size 1.27 1.27)
				)
				(justify mirror)
			)
		)
		(property "Value" ""
			(at 0 0 90)
			(layer "B.Fab")
			(effects
				(font
					(size 1.27 1.27)
				)
				(justify mirror)
			)
		)
		(duplicate_pad_numbers_are_jumpers no)
		(fp_line
			(start -0.299974 0.150114)
			(end 0.299974 0.150114)
			(stroke
				(width 0.1)
				(type default)
			)
			(layer "B.Fab")
		)
		(fp_line
			(start 0.299974 0.150114)
			(end 0.299974 -0.150114)
			(stroke
				(width 0.1)
				(type default)
			)
			(layer "B.Fab")
		)
		(fp_line
			(start -0.299974 -0.150114)
			(end -0.299974 0.150114)
			(stroke
				(width 0.1)
				(type default)
			)
			(layer "B.Fab")
		)
		(fp_line
			(start 0.299974 -0.150114)
			(end -0.299974 -0.150114)
			(stroke
				(width 0.1)
				(type default)
			)
			(layer "B.Fab")
		)
		(pad "1" smd rect
			(at 0.2667 0 90)
			(size 0.3048 0.381)
			(layers "B.Cu" "B.Mask" "B.Paste")
			(net "P0V9_CPU1_RT3_2A_2D")
		)
		(pad "2" smd rect
			(at -0.2667 0 90)
			(size 0.3048 0.381)
			(layers "B.Cu" "B.Mask" "B.Paste")
			(net "GND")
		)
	)
	(footprint ""
		(layer "B.Cu")
		(at 396.797276 -177.294794 -90)
		(property "Reference" "PC589_1"
			(at 0 0 90)
			(layer "B.SilkS")
			(hide yes)
			(effects
				(font
					(size 1.27 1.27)
				)
				(justify mirror)
			)
		)
		(property "Value" ""
			(at 0 0 90)
			(layer "B.Fab")
			(effects
				(font
					(size 1.27 1.27)
				)
				(justify mirror)
			)
		)
		(duplicate_pad_numbers_are_jumpers no)
		(fp_line
			(start -1.524 0.762)
			(end 1.524 0.762)
			(stroke
				(width 0.1524)
				(type default)
			)
			(layer "B.SilkS")
		)
		(fp_line
			(start 1.524 0.762)
			(end 1.524 -0.762)
			(stroke
				(width 0.1524)
				(type default)
			)
			(layer "B.SilkS")
		)
		(fp_line
			(start -1.524 -0.762)
			(end -1.524 0.762)
			(stroke
				(width 0.1524)
				(type default)
			)
			(layer "B.SilkS")
		)
		(fp_line
			(start 1.524 -0.762)
			(end -1.524 -0.762)
			(stroke
				(width 0.1524)
				(type default)
			)
			(layer "B.SilkS")
		)
		(fp_line
			(start -1.1049 0.724916)
			(end -1.1049 -0.724916)
			(stroke
				(width 0.1)
				(type default)
			)
			(layer "B.Fab")
		)
		(fp_line
			(start 1.1049 0.724916)
			(end -1.1049 0.724916)
			(stroke
				(width 0.1)
				(type default)
			)
			(layer "B.Fab")
		)
		(fp_line
			(start -1.1049 -0.724916)
			(end 1.1049 -0.724916)
			(stroke
				(width 0.1)
				(type default)
			)
			(layer "B.Fab")
		)
		(fp_line
			(start 1.1049 -0.724916)
			(end 1.1049 0.724916)
			(stroke
				(width 0.1)
				(type default)
			)
			(layer "B.Fab")
		)
		(pad "1" smd rect
			(at 0.889 0 270)
			(size 1.016 1.27)
			(layers "B.Cu" "B.Mask" "B.Paste")
			(net "SW_P12V_AUX_PVDDCR_SOC_P0_FLT")
		)
		(pad "2" smd rect
			(at -0.889 0 270)
			(size 1.016 1.27)
			(layers "B.Cu" "B.Mask" "B.Paste")
			(net "GND")
		)
	)
	(footprint ""
		(layer "B.Cu")
		(at 323.039994 -337.653376 -90)
		(property "Reference" "PR83"
			(at 0 0 90)
			(layer "B.SilkS")
			(hide yes)
			(effects
				(font
					(size 1.27 1.27)
				)
				(justify mirror)
			)
		)
		(property "Value" ""
			(at 0 0 90)
			(layer "B.Fab")
			(effects
				(font
					(size 1.27 1.27)
				)
				(justify mirror)
			)
		)
		(duplicate_pad_numbers_are_jumpers no)
		(fp_line
			(start -0.7874 0.4064)
			(end 0.7874 0.4064)
			(stroke
				(width 0.1524)
				(type default)
			)
			(layer "B.SilkS")
		)
		(fp_line
			(start 0.7874 0.4064)
			(end 0.7874 -0.4064)
			(stroke
				(width 0.1524)
				(type default)
			)
			(layer "B.SilkS")
		)
		(fp_line
			(start -0.7874 -0.4064)
			(end -0.7874 0.4064)
			(stroke
				(width 0.1524)
				(type default)
			)
			(layer "B.SilkS")
		)
		(fp_line
			(start 0.7874 -0.4064)
			(end -0.7874 -0.4064)
			(stroke
				(width 0.1524)
				(type default)
			)
			(layer "B.SilkS")
		)
		(fp_line
			(start -0.67945 0.3048)
			(end -0.120396 0.3048)
			(stroke
				(width 0.1)
				(type default)
			)
			(layer "B.Fab")
		)
		(fp_line
			(start -0.120396 0.3048)
			(end -0.120396 0.2794)
			(stroke
				(width 0.1)
				(type default)
			)
			(layer "B.Fab")
		)
		(fp_line
			(start 0.12065 0.3048)
			(end 0.67945 0.3048)
			(stroke
				(width 0.1)
				(type default)
			)
			(layer "B.Fab")
		)
		(fp_line
			(start 0.67945 0.3048)
			(end 0.67945 -0.305054)
			(stroke
				(width 0.1)
				(type default)
			)
			(layer "B.Fab")
		)
		(fp_line
			(start -0.120396 0.2794)
			(end 0.12065 0.2794)
			(stroke
				(width 0.1)
				(type default)
			)
			(layer "B.Fab")
		)
		(fp_line
			(start 0.12065 0.2794)
			(end 0.12065 0.3048)
			(stroke
				(width 0.1)
				(type default)
			)
			(layer "B.Fab")
		)
		(fp_line
			(start -0.12065 -0.2794)
			(end -0.12065 -0.3048)
			(stroke
				(width 0.1)
				(type default)
			)
			(layer "B.Fab")
		)
		(fp_line
			(start 0.12065 -0.2794)
			(end -0.12065 -0.2794)
			(stroke
				(width 0.1)
				(type default)
			)
			(layer "B.Fab")
		)
		(fp_line
			(start -0.67945 -0.3048)
			(end -0.67945 0.3048)
			(stroke
				(width 0.1)
				(type default)
			)
			(layer "B.Fab")
		)
		(fp_line
			(start -0.12065 -0.3048)
			(end -0.67945 -0.3048)
			(stroke
				(width 0.1)
				(type default)
			)
			(layer "B.Fab")
		)
		(fp_line
			(start 0.12065 -0.305054)
			(end 0.12065 -0.2794)
			(stroke
				(width 0.1)
				(type default)
			)
			(layer "B.Fab")
		)
		(fp_line
			(start 0.67945 -0.305054)
			(end 0.12065 -0.305054)
			(stroke
				(width 0.1)
				(type default)
			)
			(layer "B.Fab")
		)
		(pad "1" smd circle
			(at 0.40005 0 90)
			(size 0 0)
			(layers "B.Cu" "B.Mask" "B.Paste")
			(net "PVDDCR_CPU1_P0_VOS2")
		)
		(pad "2" smd circle
			(at -0.40005 0 90)
			(size 0 0)
			(layers "B.Cu" "B.Mask" "B.Paste")
			(net "PVDDCR_CPU1_P0")
		)
	)
)
